# Barreleye G2-MB-DVT-PROGRAM IC LIST-X03-20170711.xlsx — Barreleye-G2 MB (ic-programming-list)
| FOXCONN TECHNOLOGY GROUP |  |  |  |  |  |  |  |  |  |  |  |  |  |  |  |
| Program IC List |  |  |  |  |  |  |  |  |  |  |  |  |  |  |  |
| Phase | EVT3 | CUSTOMER |  | RACKSPACE | PWA CUSTOMER P/N |  | PWA FOXCONN P/N | TBD | PWA DESCRIPTION | Barreleye-G2 MB | PRODUCT CODE | PBA REV | X02 | DATE | 42782 |
| Location | Function | Source code version | Program Type | Bin File | Empty IC  FOXCONN PN | Empty IC  Supplier PN | Programmed IC  FOXCONN PN | CheckSUM | Program Spec | Source Code Release Date | From Whom | Comment |  |  |  |
| U37 | USB controller UPD720201, EEPROM | 0.0.1 | Off-line |  | 41050J100-233-G | MX25L5121EMC-20G | NA | 005E79C6 |  | 42853 | TAIWAN SATORI RENESAS | Updated EEPROM for 4-port enable for DVT |  |  |  |
| U46 | SATA Controller 88SE9235, FLASH | 0.0.0 | Off-line |  | 41050K700-233-G | MX25L4006EM2I-12G | NA | 03B75FF7 |  | 42401 | Marvell | As same as EVT3 |  |  |  |
| U_LOM1_ROM1 | LOM BCM5719,FLASH | 0.0.0 | Off-line |  | 41050W700-46Y-G | AT45DB081E-SHNHC-T | NA | 05B5D2E9 |  | 42628 | Broadcom | As same as EVT3 |  |  |  |
| U20 | BMC AST2500, 512Mb Flash | 0.50.B-RAX | Off-line |  | 410512F00-233-G | MX66L51235FMI-10G | NA | 663F9766 |  | 42927 | FXN | For DVT build Update for G2 Tri-mode solutions |  |  |  |
| U21 | BIOS, 512Mb Flash | NA | Off-line |  | 410512F00-233-G | MX66L51235FMI-10G | NA | 903E132D |  | 42782 | Google | For DVT build |  |  |  |
| U98 | VPD, EEPROM | DVT | Off-line | IBM | 410403P00-214-G | M24512-WMN6TP | NA | 0003AD34 |  | 42878 | IBM | For DVT build IBM updated on 5/23 |  |  |  |
| U30 | FRU, EEPROM | 0.0.0 | Off-line | FXN | 41040BT00-191-G | AT24C64D-SSHM-T | NA | 00002900 |  | 42622 | FXN | Barreleye-G2 MB FRU As same as EVT3 |  |  |  |
| PAAU1,PBAU1,PAMU1,PBMU1,PAEU1,PAFU1,PBEU1,PBFU1 | VR Controller, ISL68137 |  | Vendor | INTERSIL | 320242200-230-G | ISL68137IRAZ-T | ISL68137IRAZ-GG04 | N/A |  | DVT | FXN | Update for fixing VCS writing issue Update MPN in DVT |  |  |  |
| PANU1,PBNU1 | VIO VR, IR38064 |  | Vendor | IR | 320147Q00-238-G | IR38064MTRPBF | IR38064MTRPBF | 8874 |  | EVT3 | FXN | Add yellow point in DVT Date code is C712P |  |  |  |
| U5 | Power Sequencer, UCD90160 |  | Vendor | FXN/TI | 320245T00-183-G | UCD90160RGCR | UCD90160RGCR-C10 | 012E2242 |  | 42877 | TI/FXN | Updated for VCS reading; Update for 1.05V power on sequence whch that meet USB3 controller's spec Update MPN in DVT |  |  |  |
